# S9S_MB_2U (Grand Teton) — schematic netlist excerpt (pin names and nets, part order shuffled) for the footprints in the layout excerpt that follows; sources: Cadence DE-HDL packaged netlist, KiCad conversion of 03242023_DA0F0TMBIJ0_F0T_Motherboard_J_brd_V01_OCP.brd

PC1853  Q_CAP  0.1UF 25V 10% X7R  pkg 0402  page 258 : A = P5V_AUX_REF ; B = GND

PL114  Q_INDUCTOR4P_14  150NH IND  pkg L_TLM117513Q-151QL_11X7-5XA  page 267
  \1\  = SW_PVCCIN_CPU0_SW1
  \2\  = IND_P0_CPL1
  \3\  = IND_P0_CPL2
  \4\  = PVCCIN_CPU0

(kicad_pcb
	(version 20260206)
	(generator "pcbnew")
	(generator_version "10.0")
	(general
		(thickness 1.6)
		(legacy_teardrops no)
	)
	(paper "A4")
	(title_block
		(title "03242023_DA0F0TMBIJ0_F0T_Motherboard_J_brd_V01_OCP.brd")
		(comment 1 "Grand Teton / footprints 3811-3812 of 6105")
	)
	(layers
		(0 "F.Cu" signal "TOP")
		(4 "In1.Cu" signal "GND")
		(6 "In2.Cu" signal "IN1")
		(8 "In3.Cu" signal "GND1")
		(10 "In4.Cu" signal "IN2")
		(12 "In5.Cu" signal "GND2")
		(14 "In6.Cu" signal "IN3")
		(16 "In7.Cu" signal "GND3")
		(18 "In8.Cu" signal "VCC")
		(20 "In9.Cu" signal "VCC1")
		(22 "In10.Cu" signal "GND4")
		(24 "In11.Cu" signal "IN4")
		(26 "In12.Cu" signal "GND5")
		(28 "In13.Cu" signal "IN5")
		(30 "In14.Cu" signal "GND6")
		(32 "In15.Cu" signal "IN6")
		(34 "In16.Cu" signal "GND7")
		(2 "B.Cu" signal "BOTTOM")
		(9 "F.Adhes" user "F.Adhesive")
		(11 "B.Adhes" user "B.Adhesive")
		(13 "F.Paste" user "Package Geometry/Pastemask Top")
		(15 "B.Paste" user "Package Geometry/Pastemask Bottom")
		(5 "F.SilkS" user "Ref Des/Silkscreen Top")
		(7 "B.SilkS" user "Ref Des/Silkscreen Bottom")
		(1 "F.Mask" user "Board Geometry/Soldermask Top")
		(3 "B.Mask" user "Board Geometry/Soldermask Bottom")
		(17 "Dwgs.User" user "User.Drawings")
		(19 "Cmts.User" user "User.Comments")
		(21 "Eco1.User" user "User.Eco1")
		(23 "Eco2.User" user "User.Eco2")
		(25 "Edge.Cuts" user "Board Geometry/Outline")
		(27 "Margin" user)
		(31 "F.CrtYd" user "Package Geometry/Place Bound Top")
		(29 "B.CrtYd" user "Package Geometry/Place Bound Bottom")
		(35 "F.Fab" user "Ref Des/Assembly Top")
		(33 "B.Fab" user "Ref Des/Assembly Bottom")
	)
	(footprint ""
		(layer "F.Cu")
		(at 344.899488 -324.445376)
		(property "Reference" "PL114"
			(at -9.220708 5.188458 0)
			(unlocked yes)
			(layer "F.SilkS")
			(effects
				(font
					(size 0.7874 0.5842)
					(thickness 0.1524)
				)
				(justify left)
			)
		)
		(property "Value" ""
			(at 0 0 0)
			(layer "F.Fab")
			(effects
				(font
					(size 1.27 1.27)
				)
			)
		)
		(duplicate_pad_numbers_are_jumpers no)
		(fp_line
			(start -3.750056 -5.500116)
			(end -2.393442 -5.500116)
			(stroke
				(width 0.1524)
				(type default)
			)
			(layer "F.SilkS")
		)
		(fp_line
			(start -3.750056 5.500116)
			(end -3.750056 -5.500116)
			(stroke
				(width 0.1524)
				(type default)
			)
			(layer "F.SilkS")
		)
		(fp_line
			(start -2.393442 5.500116)
			(end -3.750056 5.500116)
			(stroke
				(width 0.1524)
				(type default)
			)
			(layer "F.SilkS")
		)
		(fp_line
			(start 2.393442 5.500116)
			(end 3.750056 5.500116)
			(stroke
				(width 0.1524)
				(type default)
			)
			(layer "F.SilkS")
		)
		(fp_line
			(start 3.750056 -5.500116)
			(end 2.393442 -5.500116)
			(stroke
				(width 0.1524)
				(type default)
			)
			(layer "F.SilkS")
		)
		(fp_line
			(start 3.750056 -4.576572)
			(end 3.750056 -5.500116)
			(stroke
				(width 0.1524)
				(type default)
			)
			(layer "F.SilkS")
		)
		(fp_line
			(start 3.750056 5.500116)
			(end 3.750056 -3.687572)
			(stroke
				(width 0.1524)
				(type default)
			)
			(layer "F.SilkS")
		)
		(fp_poly
			(pts
				(xy -3.280664 -7.074154) (xy -2.921508 -5.996432) (xy -3.998976 -6.355842)
			)
			(stroke
				(width 0)
				(type default)
			)
			(fill yes)
			(layer "F.SilkS")
		)
		(fp_line
			(start -3.750056 -5.500116)
			(end -3.750056 5.500116)
			(stroke
				(width 0.1)
				(type default)
			)
			(layer "F.Fab")
		)
		(fp_line
			(start -3.750056 5.500116)
			(end 3.750056 5.500116)
			(stroke
				(width 0.1)
				(type default)
			)
			(layer "F.Fab")
		)
		(fp_line
			(start 3.750056 -5.500116)
			(end -3.750056 -5.500116)
			(stroke
				(width 0.1)
				(type default)
			)
			(layer "F.Fab")
		)
		(fp_line
			(start 3.750056 5.500116)
			(end 3.750056 -5.500116)
			(stroke
				(width 0.1)
				(type default)
			)
			(layer "F.Fab")
		)
		(fp_poly
			(pts
				(xy -4.9276 -4.757928) (xy -4.9276 -3.741928) (xy -3.9116 -4.249928)
			)
			(stroke
				(width 0)
				(type default)
			)
			(fill yes)
			(layer "F.Fab")
		)
		(pad "1" smd rect
			(at 0 -4.249928 270)
			(size 2.413 4.5212)
			(layers "F.Cu" "F.Mask" "F.Paste")
			(net "SW_PVCCIN_CPU0_SW1")
		)
		(pad "2" smd rect
			(at 0 -1.175004 270)
			(size 1.3716 4.5212)
			(layers "F.Cu" "F.Mask" "F.Paste")
			(net "IND_P0_CPL1")
		)
		(pad "3" smd rect
			(at 0 1.175004 270)
			(size 1.3716 4.5212)
			(layers "F.Cu" "F.Mask" "F.Paste")
			(net "IND_P0_CPL2")
		)
		(pad "4" smd rect
			(at 0 4.249928 270)
			(size 2.413 4.5212)
			(layers "F.Cu" "F.Mask" "F.Paste")
			(net "PVCCIN_CPU0")
		)
	)
	(footprint ""
		(layer "F.Cu")
		(at 457.7461 -381.24892 -90)
		(property "Reference" "PC1853"
			(at 0 0 270)
			(layer "F.SilkS")
			(hide yes)
			(effects
				(font
					(size 1.27 1.27)
				)
			)
		)
		(property "Value" ""
			(at 0 0 270)
			(layer "F.Fab")
			(effects
				(font
					(size 1.27 1.27)
				)
			)
		)
		(duplicate_pad_numbers_are_jumpers no)
		(fp_line
			(start -0.7874 0.4064)
			(end -0.7874 -0.4064)
			(stroke
				(width 0.1524)
				(type default)
			)
			(layer "F.SilkS")
		)
		(fp_line
			(start 0.7874 0.4064)
			(end -0.7874 0.4064)
			(stroke
				(width 0.1524)
				(type default)
			)
			(layer "F.SilkS")
		)
		(fp_line
			(start -0.7874 -0.4064)
			(end 0.7874 -0.4064)
			(stroke
				(width 0.1524)
				(type default)
			)
			(layer "F.SilkS")
		)
		(fp_line
			(start 0.7874 -0.4064)
			(end 0.7874 0.4064)
			(stroke
				(width 0.1524)
				(type default)
			)
			(layer "F.SilkS")
		)
		(fp_line
			(start -0.67945 0.3048)
			(end -0.67945 -0.305054)
			(stroke
				(width 0.1)
				(type default)
			)
			(layer "F.Fab")
		)
		(fp_line
			(start -0.12065 0.3048)
			(end -0.67945 0.3048)
			(stroke
				(width 0.1)
				(type default)
			)
			(layer "F.Fab")
		)
		(fp_line
			(start 0.120396 0.3048)
			(end 0.120396 0.2794)
			(stroke
				(width 0.1)
				(type default)
			)
			(layer "F.Fab")
		)
		(fp_line
			(start 0.67945 0.3048)
			(end 0.120396 0.3048)
			(stroke
				(width 0.1)
				(type default)
			)
			(layer "F.Fab")
		)
		(fp_line
			(start -0.12065 0.2794)
			(end -0.12065 0.3048)
			(stroke
				(width 0.1)
				(type default)
			)
			(layer "F.Fab")
		)
		(fp_line
			(start 0.120396 0.2794)
			(end -0.12065 0.2794)
			(stroke
				(width 0.1)
				(type default)
			)
			(layer "F.Fab")
		)
		(fp_line
			(start -0.12065 -0.2794)
			(end 0.12065 -0.2794)
			(stroke
				(width 0.1)
				(type default)
			)
			(layer "F.Fab")
		)
		(fp_line
			(start 0.12065 -0.2794)
			(end 0.12065 -0.3048)
			(stroke
				(width 0.1)
				(type default)
			)
			(layer "F.Fab")
		)
		(fp_line
			(start 0.12065 -0.3048)
			(end 0.67945 -0.3048)
			(stroke
				(width 0.1)
				(type default)
			)
			(layer "F.Fab")
		)
		(fp_line
			(start 0.67945 -0.3048)
			(end 0.67945 0.3048)
			(stroke
				(width 0.1)
				(type default)
			)
			(layer "F.Fab")
		)
		(fp_line
			(start -0.67945 -0.305054)
			(end -0.12065 -0.305054)
			(stroke
				(width 0.1)
				(type default)
			)
			(layer "F.Fab")
		)
		(fp_line
			(start -0.12065 -0.305054)
			(end -0.12065 -0.2794)
			(stroke
				(width 0.1)
				(type default)
			)
			(layer "F.Fab")
		)
		(pad "1" smd circle
			(at -0.40005 0 270)
			(size 0 0)
			(layers "F.Cu" "F.Mask" "F.Paste")
			(net "P5V_AUX_REF")
		)
		(pad "2" smd circle
			(at 0.40005 0 270)
			(size 0 0)
			(layers "F.Cu" "F.Mask" "F.Paste")
			(net "GND")
		)
	)
)
